# BASEBOARD_FAB2 (Tioga Pass) — schematic netlist excerpt (pin names and nets, part order shuffled) for the footprints in the layout excerpt that follows; sources: Cadence DE-HDL packaged netlist, KiCad conversion of Wiwynn_Tioga_Pass_MB.brd

C8T5  CAP_A  47UF 4V 20% X5R  pkg 0603V  page 225 : A = PVDDQ_GHJ ; B = GND
C22W26  SC22U16V5MX-4-GP  20%  pkg SMD-BCG5  page 236 : \1\ = VR_FET_SW_P12V_STBY_PVDDQ_DEF ; \2\ = GND

U25W13  MAX4564EKA-GP  pkg SCRET-GC1  page 254
  NC  = JTAG_BMC_TCK0
  \v+\  = P3V3_STBY
  \in\  = BMC_TCK_MUX_SEL
  NO  = JTAG_BMC_TCK1
  GND  = GND
  \v-\  = GND
  \en#\  = BMC_JTAG_SEL_N
  COM  = JTAG_BMC_TCK_BUF

(kicad_pcb
	(version 20260206)
	(generator "pcbnew")
	(generator_version "10.0")
	(general
		(thickness 1.6)
		(legacy_teardrops no)
	)
	(paper "A4")
	(title_block
		(title "Wiwynn_Tioga_Pass_MB.brd")
		(comment 1 "Tioga Pass / footprints 3130-3132 of 4770")
	)
	(layers
		(0 "F.Cu" signal "TOP")
		(4 "In1.Cu" signal "L2GND")
		(6 "In2.Cu" signal "L3")
		(8 "In3.Cu" signal "L4GND")
		(10 "In4.Cu" signal "L5")
		(12 "In5.Cu" signal "L6GND")
		(14 "In6.Cu" signal "L7VCC")
		(16 "In7.Cu" signal "L8VCC")
		(18 "In8.Cu" signal "L9GND")
		(20 "In9.Cu" signal "L10")
		(22 "In10.Cu" signal "L11GND")
		(24 "In11.Cu" signal "L12")
		(26 "In12.Cu" signal "L13GND")
		(2 "B.Cu" signal "BOTTOM")
		(9 "F.Adhes" user "F.Adhesive")
		(11 "B.Adhes" user "B.Adhesive")
		(13 "F.Paste" user "Package Geometry/Pastemask Top")
		(15 "B.Paste" user "Package Geometry/Pastemask Bottom")
		(5 "F.SilkS" user "Ref Des/Silkscreen Top")
		(7 "B.SilkS" user "Ref Des/Silkscreen Bottom")
		(1 "F.Mask" user "Board Geometry/Soldermask Top")
		(3 "B.Mask" user "Board Geometry/Soldermask Bottom")
		(17 "Dwgs.User" user "User.Drawings")
		(19 "Cmts.User" user "User.Comments")
		(21 "Eco1.User" user "User.Eco1")
		(23 "Eco2.User" user "User.Eco2")
		(25 "Edge.Cuts" user "Board Geometry/Outline")
		(27 "Margin" user)
		(31 "F.CrtYd" user "Package Geometry/Place Bound Top")
		(29 "B.CrtYd" user "Package Geometry/Place Bound Bottom")
		(35 "F.Fab" user "Ref Des/Assembly Top")
		(33 "B.Fab" user "Ref Des/Assembly Bottom")
	)
	(footprint ""
		(layer "B.Cu")
		(at 439.301636 -144.935956 180)
		(property "Reference" "U25W13"
			(at 0 0 0)
			(layer "B.SilkS")
			(hide yes)
			(effects
				(font
					(size 1.27 1.27)
				)
				(justify mirror)
			)
		)
		(property "Value" "*"
			(at 5.08 -8.52805 180)
			(unlocked yes)
			(layer "B.Fab")
			(hide yes)
			(effects
				(font
					(size 0.889 0.889)
					(thickness 0.1524)
				)
				(justify mirror)
			)
		)
		(property "Device Type" "MAX4564EKA-GP_SCRET-GC1-MAX456A"
			(at 5.08 -10.05205 180)
			(unlocked yes)
			(layer "B.Fab")
			(hide yes)
			(effects
				(font
					(size 0.889 0.889)
					(thickness 0.1524)
				)
				(justify mirror)
			)
		)
		(duplicate_pad_numbers_are_jumpers no)
		(fp_line
			(start 1.8796 0.5588)
			(end 1.8796 -0.5588)
			(stroke
				(width 0.1524)
				(type default)
			)
			(layer "B.SilkS")
		)
		(fp_line
			(start 1.8796 -0.254)
			(end 1.6256 0)
			(stroke
				(width 0.1524)
				(type default)
			)
			(layer "B.SilkS")
		)
		(fp_line
			(start 1.8796 -0.5588)
			(end -1.8796 -0.5588)
			(stroke
				(width 0.1524)
				(type default)
			)
			(layer "B.SilkS")
		)
		(fp_line
			(start 1.7018 0.5588)
			(end 1.7018 2.1082)
			(stroke
				(width 0.508)
				(type default)
			)
			(layer "B.SilkS")
		)
		(fp_line
			(start 1.6256 0)
			(end 1.8796 0.254)
			(stroke
				(width 0.1524)
				(type default)
			)
			(layer "B.SilkS")
		)
		(fp_line
			(start -1.8796 0.5588)
			(end 1.8796 0.5588)
			(stroke
				(width 0.1524)
				(type default)
			)
			(layer "B.SilkS")
		)
		(fp_line
			(start -1.8796 -0.5588)
			(end -1.8796 0.5588)
			(stroke
				(width 0.1524)
				(type default)
			)
			(layer "B.SilkS")
		)
		(fp_poly
			(pts
				(xy 1.15316 0.5588) (xy -1.8796 0.5588) (xy -1.8796 -0.5588) (xy 1.15316 -0.5588)
			)
			(stroke
				(width 0)
				(type default)
			)
			(fill yes)
			(layer "B.SilkS")
		)
		(fp_rect
			(start 1.9558 2.3622)
			(end -1.9558 -2.3622)
			(stroke
				(width 0)
				(type default)
			)
			(fill no)
			(layer "B.CrtYd")
		)
		(fp_poly
			(pts
				(xy 1.9558 -2.3622) (xy -1.9558 -2.3622) (xy -1.9558 2.3622) (xy 1.9558 2.3622)
			)
			(stroke
				(width 0)
				(type default)
			)
			(fill no)
			(layer "B.Fab")
		)
		(pad "1" smd rect
			(at 0.97536 1.3462)
			(size 0.3556 1.016)
			(layers "B.Cu" "B.Mask" "B.Paste")
			(net "JTAG_BMC_TCK0")
		)
		(pad "2" smd rect
			(at 0.32512 1.3462)
			(size 0.3556 1.016)
			(layers "B.Cu" "B.Mask" "B.Paste")
			(net "P3V3_STBY")
		)
		(pad "3" smd rect
			(at -0.32512 1.3462)
			(size 0.3556 1.016)
			(layers "B.Cu" "B.Mask" "B.Paste")
			(net "BMC_TCK_MUX_SEL")
		)
		(pad "4" smd rect
			(at -0.97409 1.3462)
			(size 0.3556 1.016)
			(layers "B.Cu" "B.Mask" "B.Paste")
			(net "JTAG_BMC_TCK1")
		)
		(pad "5" smd rect
			(at -0.97409 -1.3462)
			(size 0.3556 1.016)
			(layers "B.Cu" "B.Mask" "B.Paste")
			(net "GND")
		)
		(pad "6" smd rect
			(at -0.32512 -1.3462)
			(size 0.3556 1.016)
			(layers "B.Cu" "B.Mask" "B.Paste")
			(net "GND")
		)
		(pad "7" smd rect
			(at 0.32512 -1.3462)
			(size 0.3556 1.016)
			(layers "B.Cu" "B.Mask" "B.Paste")
			(net "BMC_JTAG_SEL_N")
		)
		(pad "8" smd rect
			(at 0.97536 -1.3462)
			(size 0.3556 1.016)
			(layers "B.Cu" "B.Mask" "B.Paste")
			(net "JTAG_BMC_TCK_BUF")
		)
	)
	(footprint ""
		(layer "B.Cu")
		(at 104.5591 -17.7546 90)
		(property "Reference" "C8T5"
			(at -1.848866 0.752348 90)
			(unlocked yes)
			(layer "B.SilkS")
			(effects
				(font
					(size 1.27 0.9652)
					(thickness 0.1524)
				)
				(justify mirror)
			)
		)
		(property "Value" ""
			(at 0 0 90)
			(layer "B.Fab")
			(effects
				(font
					(size 1.27 1.27)
				)
				(justify mirror)
			)
		)
		(duplicate_pad_numbers_are_jumpers no)
		(fp_rect
			(start 0.500126 1.598422)
			(end -0.500126 -0.201422)
			(stroke
				(width 0)
				(type default)
			)
			(fill no)
			(layer "B.CrtYd")
		)
		(fp_line
			(start 0.500126 -0.201422)
			(end -0.500126 -0.201422)
			(stroke
				(width 0.1)
				(type default)
			)
			(layer "B.Fab")
		)
		(fp_line
			(start -0.500126 -0.201422)
			(end -0.500126 1.598422)
			(stroke
				(width 0.1)
				(type default)
			)
			(layer "B.Fab")
		)
		(fp_line
			(start 0.500126 1.598422)
			(end 0.500126 -0.201422)
			(stroke
				(width 0.1)
				(type default)
			)
			(layer "B.Fab")
		)
		(fp_line
			(start -0.500126 1.598422)
			(end 0.500126 1.598422)
			(stroke
				(width 0.1)
				(type default)
			)
			(layer "B.Fab")
		)
		(pad "1" smd rect
			(at 0 0)
			(size 0.889 0.9906)
			(layers "B.Cu" "B.Mask" "B.Paste")
			(net "PVDDQ_GHJ")
		)
		(pad "2" smd rect
			(at 0 1.397)
			(size 0.889 0.9906)
			(layers "B.Cu" "B.Mask" "B.Paste")
			(net "GND")
		)
		(zone
			(layer "B.Cu")
			(hatch none 0.5)
			(connect_pads
				(clearance 0)
			)
			(min_thickness 0.25)
			(keepout
				(tracks not_allowed)
				(vias allowed)
				(pads allowed)
				(copperpour not_allowed)
				(footprints allowed)
			)
			(placement
				(enabled no)
				(sheetname "")
			)
			(fill
				(thermal_gap 0.5)
				(thermal_bridge_width 0.5)
				(island_removal_mode 0)
			)
			(polygon
				(pts
					(xy 105.5116 -18.2499) (xy 105.0036 -18.2499) (xy 105.0036 -17.2593) (xy 105.5116 -17.2593)
				)
			)
		)
		(zone
			(layer "B.Cu")
			(hatch none 0.5)
			(connect_pads
				(clearance 0)
			)
			(min_thickness 0.25)
			(keepout
				(tracks allowed)
				(vias not_allowed)
				(pads allowed)
				(copperpour not_allowed)
				(footprints allowed)
			)
			(placement
				(enabled no)
				(sheetname "")
			)
			(fill
				(thermal_gap 0.5)
				(thermal_bridge_width 0.5)
				(island_removal_mode 0)
			)
			(polygon
				(pts
					(xy 105.5116 -18.2499) (xy 105.0036 -18.2499) (xy 105.0036 -17.2593) (xy 105.5116 -17.2593)
				)
			)
		)
	)
	(footprint ""
		(layer "B.Cu")
		(at 365.936276 -156.15158 180)
		(property "Reference" "C22W26"
			(at 0 0 0)
			(layer "B.SilkS")
			(hide yes)
			(effects
				(font
					(size 1.27 1.27)
				)
				(justify mirror)
			)
		)
		(property "Value" "*"
			(at 0.0762 -6.2357 180)
			(unlocked yes)
			(layer "B.Fab")
			(hide yes)
			(effects
				(font
					(size 1.27 1.016)
					(thickness 0.1524)
				)
				(justify mirror)
			)
		)
		(property "Device Type" "SC22U16V5MX-4-GP_SMD-BCG5-SC22A"
			(at 0.0762 -8.2677 180)
			(unlocked yes)
			(layer "B.Fab")
			(hide yes)
			(effects
				(font
					(size 1.27 1.016)
					(thickness 0.1524)
				)
				(justify mirror)
			)
		)
		(duplicate_pad_numbers_are_jumpers no)
		(fp_line
			(start -0.635 0)
			(end 0.635 0)
			(stroke
				(width 0.508)
				(type default)
			)
			(layer "B.SilkS")
		)
		(fp_rect
			(start 0.9652 1.778)
			(end -0.9652 -1.778)
			(stroke
				(width 0)
				(type default)
			)
			(fill no)
			(layer "B.CrtYd")
		)
		(fp_poly
			(pts
				(xy 0.9652 -1.778) (xy -0.9652 -1.778) (xy -0.9652 1.778) (xy 0.9652 1.778)
			)
			(stroke
				(width 0)
				(type default)
			)
			(fill no)
			(layer "B.Fab")
		)
		(pad "1" smd rect
			(at 0 -0.9652)
			(size 1.397 1.143)
			(layers "B.Cu" "B.Mask" "B.Paste")
			(net "VR_FET_SW_P12V_STBY_PVDDQ_DEF")
		)
		(pad "2" smd rect
			(at 0 0.9652)
			(size 1.397 1.143)
			(layers "B.Cu" "B.Mask" "B.Paste")
			(net "GND")
		)
	)
)
